#ISCELL
  mstr_misc dns *
  *
#ISCELL
  mstr_symbols cad_note *
  *
#ISCELL
  mstr_symbols design_note *
  *
#ISCELL
  mstr_symbols intel_corp_bpage *
  *
#CELL
  mstr_discrete res *
  page166_i11
#CELL
  mstr_discrete res *
  page166_i14
#CELL
  mstr_discrete res *
  page166_i15
#ISCELL
  mstr_standard offpage *
  page166_i16
#ISCELL
  mstr_standard offpage *
  page166_i17
#ISCELL
  mstr_standard offpage *
  page166_i2
#CELL
  mstr_discrete res *
  page166_i28
#ISCELL
  mstr_symbols pvccio_cpu0 *
  page166_i31
#CELL
  mstr_discrete res *
  page166_i32
#ISCELL
  mstr_symbols gnd *
  page166_i33
